# S9S_MB_2U (Grand Teton) — schematic netlist excerpt (pin names and nets, part order shuffled) for the footprints in the layout excerpt that follows; sources: Cadence DE-HDL packaged netlist, KiCad conversion of 03242023_DA0F0TMBIJ0_F0T_Motherboard_J_brd_V01_OCP.brd

R628  Q_RES  10K 1% CHIP  pkg 0402LF  page 127 : A = PD_PIROM_CPU1_ADDR1 ; B = GND

(kicad_pcb
	(version 20260206)
	(generator "pcbnew")
	(generator_version "10.0")
	(general
		(thickness 1.6)
		(legacy_teardrops no)
	)
	(paper "A4")
	(title_block
		(title "03242023_DA0F0TMBIJ0_F0T_Motherboard_J_brd_V01_OCP.brd")
		(comment 1 "Grand Teton / footprints 383-383 of 6105")
	)
	(layers
		(0 "F.Cu" signal "TOP")
		(4 "In1.Cu" signal "GND")
		(6 "In2.Cu" signal "IN1")
		(8 "In3.Cu" signal "GND1")
		(10 "In4.Cu" signal "IN2")
		(12 "In5.Cu" signal "GND2")
		(14 "In6.Cu" signal "IN3")
		(16 "In7.Cu" signal "GND3")
		(18 "In8.Cu" signal "VCC")
		(20 "In9.Cu" signal "VCC1")
		(22 "In10.Cu" signal "GND4")
		(24 "In11.Cu" signal "IN4")
		(26 "In12.Cu" signal "GND5")
		(28 "In13.Cu" signal "IN5")
		(30 "In14.Cu" signal "GND6")
		(32 "In15.Cu" signal "IN6")
		(34 "In16.Cu" signal "GND7")
		(2 "B.Cu" signal "BOTTOM")
		(9 "F.Adhes" user "F.Adhesive")
		(11 "B.Adhes" user "B.Adhesive")
		(13 "F.Paste" user "Package Geometry/Pastemask Top")
		(15 "B.Paste" user "Package Geometry/Pastemask Bottom")
		(5 "F.SilkS" user "Ref Des/Silkscreen Top")
		(7 "B.SilkS" user "Ref Des/Silkscreen Bottom")
		(1 "F.Mask" user "Board Geometry/Soldermask Top")
		(3 "B.Mask" user "Board Geometry/Soldermask Bottom")
		(17 "Dwgs.User" user "User.Drawings")
		(19 "Cmts.User" user "User.Comments")
		(21 "Eco1.User" user "User.Eco1")
		(23 "Eco2.User" user "User.Eco2")
		(25 "Edge.Cuts" user "Board Geometry/Outline")
		(27 "Margin" user)
		(31 "F.CrtYd" user "Package Geometry/Place Bound Top")
		(29 "B.CrtYd" user "Package Geometry/Place Bound Bottom")
		(35 "F.Fab" user "Ref Des/Assembly Top")
		(33 "B.Fab" user "Ref Des/Assembly Bottom")
	)
	(footprint ""
		(layer "F.Cu")
		(at 193.90868 -358.206548)
		(property "Reference" "R628"
			(at 0 0 0)
			(layer "F.SilkS")
			(hide yes)
			(effects
				(font
					(size 1.27 1.27)
				)
			)
		)
		(property "Value" ""
			(at 0 0 0)
			(layer "F.Fab")
			(effects
				(font
					(size 1.27 1.27)
				)
			)
		)
		(duplicate_pad_numbers_are_jumpers no)
		(fp_line
			(start -0.7874 -0.4064)
			(end 0.7874 -0.4064)
			(stroke
				(width 0.1524)
				(type default)
			)
			(layer "F.SilkS")
		)
		(fp_line
			(start -0.7874 0.4064)
			(end -0.7874 -0.4064)
			(stroke
				(width 0.1524)
				(type default)
			)
			(layer "F.SilkS")
		)
		(fp_line
			(start 0.7874 -0.4064)
			(end 0.7874 0.4064)
			(stroke
				(width 0.1524)
				(type default)
			)
			(layer "F.SilkS")
		)
		(fp_line
			(start 0.7874 0.4064)
			(end -0.7874 0.4064)
			(stroke
				(width 0.1524)
				(type default)
			)
			(layer "F.SilkS")
		)
		(fp_line
			(start -0.67945 -0.305054)
			(end -0.12065 -0.305054)
			(stroke
				(width 0.1)
				(type default)
			)
			(layer "F.Fab")
		)
		(fp_line
			(start -0.67945 0.3048)
			(end -0.67945 -0.305054)
			(stroke
				(width 0.1)
				(type default)
			)
			(layer "F.Fab")
		)
		(fp_line
			(start -0.12065 -0.305054)
			(end -0.12065 -0.2794)
			(stroke
				(width 0.1)
				(type default)
			)
			(layer "F.Fab")
		)
		(fp_line
			(start -0.12065 -0.2794)
			(end 0.12065 -0.2794)
			(stroke
				(width 0.1)
				(type default)
			)
			(layer "F.Fab")
		)
		(fp_line
			(start -0.12065 0.2794)
			(end -0.12065 0.3048)
			(stroke
				(width 0.1)
				(type default)
			)
			(layer "F.Fab")
		)
		(fp_line
			(start -0.12065 0.3048)
			(end -0.67945 0.3048)
			(stroke
				(width 0.1)
				(type default)
			)
			(layer "F.Fab")
		)
		(fp_line
			(start 0.120396 0.2794)
			(end -0.12065 0.2794)
			(stroke
				(width 0.1)
				(type default)
			)
			(layer "F.Fab")
		)
		(fp_line
			(start 0.120396 0.3048)
			(end 0.120396 0.2794)
			(stroke
				(width 0.1)
				(type default)
			)
			(layer "F.Fab")
		)
		(fp_line
			(start 0.12065 -0.3048)
			(end 0.67945 -0.3048)
			(stroke
				(width 0.1)
				(type default)
			)
			(layer "F.Fab")
		)
		(fp_line
			(start 0.12065 -0.2794)
			(end 0.12065 -0.3048)
			(stroke
				(width 0.1)
				(type default)
			)
			(layer "F.Fab")
		)
		(fp_line
			(start 0.67945 -0.3048)
			(end 0.67945 0.3048)
			(stroke
				(width 0.1)
				(type default)
			)
			(layer "F.Fab")
		)
		(fp_line
			(start 0.67945 0.3048)
			(end 0.120396 0.3048)
			(stroke
				(width 0.1)
				(type default)
			)
			(layer "F.Fab")
		)
		(pad "1" smd circle
			(at -0.40005 0)
			(size 0 0)
			(layers "F.Cu" "F.Mask" "F.Paste")
			(net "PD_PIROM_CPU1_ADDR1")
		)
		(pad "2" smd circle
			(at 0.40005 0)
			(size 0 0)
			(layers "F.Cu" "F.Mask" "F.Paste")
			(net "GND")
		)
	)
)
